(kicad_pcb
	(version 20241229)
	(generator "pcbnew")
	(generator_version "9.0")
	(general
		(thickness 1.62)
		(legacy_teardrops no)
	)
	(paper "A4")
	(title_block
		(title "OCuLink to 10GbE adapter")
		(date "2026-02-23")
		(rev "1.1.0")
		(company "Antmicro Ltd")
		(comment 1 "www.antmicro.com")
		(comment 9 "footprint 265 of 510 (U9), pads 85-165 of 503")
	)
	(layers
		(0 "F.Cu" signal)
		(4 "In1.Cu" signal)
		(6 "In2.Cu" signal)
		(8 "In3.Cu" signal)
		(10 "In4.Cu" signal)
		(12 "In5.Cu" signal)
		(14 "In6.Cu" signal)
		(2 "B.Cu" signal)
		(9 "F.Adhes" user "F.Adhesive")
		(11 "B.Adhes" user "B.Adhesive")
		(13 "F.Paste" user)
		(15 "B.Paste" user)
		(5 "F.SilkS" user "F.Silkscreen")
		(7 "B.SilkS" user "B.Silkscreen")
		(1 "F.Mask" user)
		(3 "B.Mask" user)
		(17 "Dwgs.User" user "User.Drawings")
		(19 "Cmts.User" user "User.Comments")
		(21 "Eco1.User" user "User.Eco1")
		(23 "Eco2.User" user "User.Eco2")
		(25 "Edge.Cuts" user)
		(27 "Margin" user)
		(31 "F.CrtYd" user "F.Courtyard")
		(29 "B.CrtYd" user "B.Courtyard")
		(35 "F.Fab" user)
		(33 "B.Fab" user)
	)
	(footprint "antmicro-footprints:FCBGA-503_22x22mm_Layout21x24_P1mm"
		(locked yes)
		(layer "F.Cu")
		(at 84.975 100 180)
		(property "Reference" "U9"
			(at -11.275 11.4 0)
			(layer "F.SilkS")
			(effects
				(font
					(size 0.7 0.7)
					(thickness 0.15)
				)
				(justify right bottom)
			)
		)
		(property "Value" "EZX710AT2_S_LMR5"
			(at -11.4 12.5 0)
			(layer "F.Fab")
			(hide yes)
			(effects
				(font
					(size 0.7 0.7)
					(thickness 0.15)
				)
				(justify right top)
			)
		)
		(property "Datasheet" "https://www.google.com/url?sa=t&source=web&rct=j&opi=89978449&url=https://cdrdv2-public.intel.com/596333/596333_X710-TM4_Datasheet_v_2_4.pdf&ved=2ahUKEwiSuv20_sCOAxXVCRAIHdxGO_UQFnoECBEQAQ&usg=AOvVaw1CjGyrGWE8ZvOdw4VBsY6U"
			(at -16.625 -13.91 0)
			(layer "F.Fab")
			(hide yes)
			(effects
				(font
					(size 0.7 0.7)
					(thickness 0.15)
				)
				(justify right top)
			)
		)
		(property "Description" "Ethernet ICs Intel Ethernet Controller 10 Gigabit X7"
			(at -12.015 -0.89 0)
			(layer "F.Fab")
			(hide yes)
			(effects
				(font
					(size 0.7 0.7)
					(thickness 0.15)
				)
				(justify right top)
			)
		)
		(property "MPN" "EZX710AT2 S LMR5"
			(at 0 0 180)
			(unlocked yes)
			(layer "F.Fab")
			(hide yes)
			(effects
				(font
					(size 1 1)
					(thickness 0.15)
				)
			)
		)
		(property "Manufacturer" "Intel"
			(at 0 0 180)
			(unlocked yes)
			(layer "F.Fab")
			(hide yes)
			(effects
				(font
					(size 1 1)
					(thickness 0.15)
				)
			)
		)
		(property "Author" "Antmicro"
			(at 0 0 180)
			(unlocked yes)
			(layer "F.Fab")
			(hide yes)
			(effects
				(font
					(size 1 1)
					(thickness 0.15)
				)
			)
		)
		(property "License" "Apache-2.0"
			(at 0 0 180)
			(unlocked yes)
			(layer "F.Fab")
			(hide yes)
			(effects
				(font
					(size 1 1)
					(thickness 0.15)
				)
			)
		)
		(sheetname "/X710-AT2 power/")
		(sheetfile "x710-at2-power.kicad_sch")
		(attr smd)
		(pad "AD4" smd circle
			(at -8.75 9.945 180)
			(size 0.5 0.5)
			(layers "F.Cu" "F.Mask" "F.Paste")
			(net 32 "/X710-AT2 PCIe/PCIe_{x4}_AC.TX0+")
			(pinfunction "PET_0_P")
			(pintype "output")
		)
		(pad "AD6" smd circle
			(at -7.75 9.945 180)
			(size 0.5 0.5)
			(layers "F.Cu" "F.Mask" "F.Paste")
			(net 28 "GND")
			(pinfunction "VSSA")
			(pintype "passive")
		)
		(pad "AD8" smd circle
			(at -6.75 9.945 180)
			(size 0.5 0.5)
			(layers "F.Cu" "F.Mask" "F.Paste")
			(net 35 "/X710-AT2 PCIe/PCIe_{x4}_AC.TX1+")
			(pinfunction "PET_1_P")
			(pintype "output")
		)
		(pad "AD10" smd circle
			(at -5.75 9.945 180)
			(size 0.5 0.5)
			(layers "F.Cu" "F.Mask" "F.Paste")
			(net 38 "/X710-AT2 PCIe/PCIe_{x4}_AC.TX1-")
			(pinfunction "PET_1_N")
			(pintype "output")
		)
		(pad "AD12" smd circle
			(at -4.75 9.945 180)
			(size 0.5 0.5)
			(layers "F.Cu" "F.Mask" "F.Paste")
			(net 28 "GND")
			(pinfunction "VSSA")
			(pintype "passive")
		)
		(pad "AD14" smd circle
			(at -3.75 9.945 180)
			(size 0.5 0.5)
			(layers "F.Cu" "F.Mask" "F.Paste")
			(net 40 "/X710-AT2 PCIe/PCIe_{x4}_AC.TX2+")
			(pinfunction "PET_2_P")
			(pintype "output")
		)
		(pad "AD16" smd circle
			(at -2.75 9.945 180)
			(size 0.5 0.5)
			(layers "F.Cu" "F.Mask" "F.Paste")
			(net 41 "/X710-AT2 PCIe/PCIe_{x4}_AC.TX2-")
			(pinfunction "PET_2_N")
			(pintype "output")
		)
		(pad "AD18" smd circle
			(at -1.75 9.945 180)
			(size 0.5 0.5)
			(layers "F.Cu" "F.Mask" "F.Paste")
			(net 28 "GND")
			(pinfunction "VSSA")
			(pintype "passive")
		)
		(pad "AD20" smd circle
			(at -0.75 9.945 180)
			(size 0.5 0.5)
			(layers "F.Cu" "F.Mask" "F.Paste")
			(net 44 "/X710-AT2 PCIe/PCIe_{x4}_AC.TX3+")
			(pinfunction "PET_3_P")
			(pintype "output")
		)
		(pad "AD22" smd circle
			(at 0.25 9.945 180)
			(size 0.5 0.5)
			(layers "F.Cu" "F.Mask" "F.Paste")
			(net 46 "/X710-AT2 PCIe/PCIe_{x4}_AC.TX3-")
			(pinfunction "PET_3_N")
			(pintype "output")
		)
		(pad "AD24" smd circle
			(at 1.25 9.945 180)
			(size 0.5 0.5)
			(layers "F.Cu" "F.Mask" "F.Paste")
			(net 28 "GND")
			(pinfunction "VSSA")
			(pintype "passive")
		)
		(pad "AD26" smd circle
			(at 2.25 9.945 180)
			(size 0.5 0.5)
			(layers "F.Cu" "F.Mask" "F.Paste")
			(net 214 "unconnected-(U9A-PET_4_P-PadAD26)")
			(pinfunction "PET_4_P")
			(pintype "output+no_connect")
		)
		(pad "AD28" smd circle
			(at 3.25 9.945 180)
			(size 0.5 0.5)
			(layers "F.Cu" "F.Mask" "F.Paste")
			(net 275 "unconnected-(U9A-PET_4_N-PadAD28)")
			(pinfunction "PET_4_N")
			(pintype "output+no_connect")
		)
		(pad "AD30" smd circle
			(at 4.25 9.945 180)
			(size 0.5 0.5)
			(layers "F.Cu" "F.Mask" "F.Paste")
			(net 28 "GND")
			(pinfunction "VSSA")
			(pintype "passive")
		)
		(pad "AD32" smd circle
			(at 5.25 9.945 180)
			(size 0.5 0.5)
			(layers "F.Cu" "F.Mask" "F.Paste")
			(net 348 "unconnected-(U9A-PET_5_N-PadAD32)")
			(pinfunction "PET_5_N")
			(pintype "output+no_connect")
		)
		(pad "AD34" smd circle
			(at 6.25 9.945 180)
			(size 0.5 0.5)
			(layers "F.Cu" "F.Mask" "F.Paste")
			(net 28 "GND")
			(pinfunction "VSSA")
			(pintype "passive")
		)
		(pad "AD36" smd circle
			(at 7.25 9.945 180)
			(size 0.5 0.5)
			(layers "F.Cu" "F.Mask" "F.Paste")
			(net 245 "unconnected-(U9A-PET_6_N-PadAD36)")
			(pinfunction "PET_6_N")
			(pintype "output+no_connect")
		)
		(pad "AD38" smd circle
			(at 8.25 9.945 180)
			(size 0.5 0.5)
			(layers "F.Cu" "F.Mask" "F.Paste")
			(net 28 "GND")
			(pinfunction "VSSA")
			(pintype "passive")
		)
		(pad "AD40" smd circle
			(at 9.25 9.945 180)
			(size 0.5 0.5)
			(layers "F.Cu" "F.Mask" "F.Paste")
			(net 164 "unconnected-(U9A-PET_7_N-PadAD40)")
			(pinfunction "PET_7_N")
			(pintype "output+no_connect")
		)
		(pad "AD42" smd circle
			(at 10.25 9.945 180)
			(size 0.5 0.5)
			(layers "F.Cu" "F.Mask" "F.Paste")
			(net 28 "GND")
			(pinfunction "VSSA")
			(pintype "passive")
		)
		(pad "B2" smd circle
			(at -9.75 -9.085 180)
			(size 0.5 0.5)
			(layers "F.Cu" "F.Mask" "F.Paste")
			(net 28 "GND")
			(pinfunction "VSSA")
			(pintype "passive")
		)
		(pad "B4" smd circle
			(at -8.75 -9.085 180)
			(size 0.5 0.5)
			(layers "F.Cu" "F.Mask" "F.Paste")
			(net 28 "GND")
			(pinfunction "VSSA")
			(pintype "passive")
		)
		(pad "B6" smd circle
			(at -7.75 -9.085 180)
			(size 0.5 0.5)
			(layers "F.Cu" "F.Mask" "F.Paste")
			(net 282 "unconnected-(U9B-SER1_RX_P-PadB6)")
			(pinfunction "SER1_RX_P")
			(pintype "input+no_connect")
		)
		(pad "B8" smd circle
			(at -6.75 -9.085 180)
			(size 0.5 0.5)
			(layers "F.Cu" "F.Mask" "F.Paste")
			(net 28 "GND")
			(pinfunction "VSSA")
			(pintype "passive")
		)
		(pad "B10" smd circle
			(at -5.75 -9.085 180)
			(size 0.5 0.5)
			(layers "F.Cu" "F.Mask" "F.Paste")
			(net 235 "unconnected-(U9B-SER1_TX_N-PadB10)")
			(pinfunction "SER1_TX_N")
			(pintype "output+no_connect")
		)
		(pad "B12" smd circle
			(at -4.75 -9.085 180)
			(size 0.5 0.5)
			(layers "F.Cu" "F.Mask" "F.Paste")
			(net 28 "GND")
			(pinfunction "VSSA")
			(pintype "passive")
		)
		(pad "B14" smd circle
			(at -3.75 -9.085 180)
			(size 0.5 0.5)
			(layers "F.Cu" "F.Mask" "F.Paste")
			(net 170 "unconnected-(U9B-SER0_RX_P-PadB14)")
			(pinfunction "SER0_RX_P")
			(pintype "input+no_connect")
		)
		(pad "B16" smd circle
			(at -2.75 -9.085 180)
			(size 0.5 0.5)
			(layers "F.Cu" "F.Mask" "F.Paste")
			(net 28 "GND")
			(pinfunction "VSSA")
			(pintype "passive")
		)
		(pad "B18" smd circle
			(at -1.75 -9.085 180)
			(size 0.5 0.5)
			(layers "F.Cu" "F.Mask" "F.Paste")
			(net 272 "unconnected-(U9B-SER0_TX_N-PadB18)")
			(pinfunction "SER0_TX_N")
			(pintype "output+no_connect")
		)
		(pad "B20" smd circle
			(at -0.75 -9.085 180)
			(size 0.5 0.5)
			(layers "F.Cu" "F.Mask" "F.Paste")
			(net 28 "GND")
			(pinfunction "VSSA")
			(pintype "passive")
		)
		(pad "B22" smd circle
			(at 0.25 -9.085 180)
			(size 0.5 0.5)
			(layers "F.Cu" "F.Mask" "F.Paste")
			(net 28 "GND")
			(pinfunction "AVSS")
			(pintype "passive")
		)
		(pad "B24" smd circle
			(at 1.25 -9.085 180)
			(size 0.5 0.5)
			(layers "F.Cu" "F.Mask" "F.Paste")
			(net 59 "/2xRJ45/Ethernet_P1.D1-")
			(pinfunction "P1_A_N")
			(pintype "bidirectional")
		)
		(pad "B26" smd circle
			(at 2.25 -9.085 180)
			(size 0.5 0.5)
			(layers "F.Cu" "F.Mask" "F.Paste")
			(net 62 "/2xRJ45/Ethernet_P1.D2+")
			(pinfunction "P1_B_P")
			(pintype "bidirectional")
		)
		(pad "B28" smd circle
			(at 3.25 -9.085 180)
			(size 0.5 0.5)
			(layers "F.Cu" "F.Mask" "F.Paste")
			(net 65 "/2xRJ45/Ethernet_P1.D3-")
			(pinfunction "P1_C_N")
			(pintype "bidirectional")
		)
		(pad "B30" smd circle
			(at 4.25 -9.085 180)
			(size 0.5 0.5)
			(layers "F.Cu" "F.Mask" "F.Paste")
			(net 67 "/2xRJ45/Ethernet_P1.D4+")
			(pinfunction "P1_D_P")
			(pintype "bidirectional")
		)
		(pad "B32" smd circle
			(at 5.25 -9.085 180)
			(size 0.5 0.5)
			(layers "F.Cu" "F.Mask" "F.Paste")
			(net 28 "GND")
			(pinfunction "AVSS")
			(pintype "passive")
		)
		(pad "B34" smd circle
			(at 6.25 -9.085 180)
			(size 0.5 0.5)
			(layers "F.Cu" "F.Mask" "F.Paste")
			(net 57 "/2xRJ45/Ethernet_P0.D4-")
			(pinfunction "P0_D_N")
			(pintype "bidirectional")
		)
		(pad "B36" smd circle
			(at 7.25 -9.085 180)
			(size 0.5 0.5)
			(layers "F.Cu" "F.Mask" "F.Paste")
			(net 58 "/2xRJ45/Ethernet_P0.D3+")
			(pinfunction "P0_C_P")
			(pintype "bidirectional")
		)
		(pad "B38" smd circle
			(at 8.25 -9.085 180)
			(size 0.5 0.5)
			(layers "F.Cu" "F.Mask" "F.Paste")
			(net 48 "/2xRJ45/Ethernet_P0.D2-")
			(pinfunction "P0_B_N")
			(pintype "bidirectional")
		)
		(pad "B40" smd circle
			(at 9.25 -9.085 180)
			(size 0.5 0.5)
			(layers "F.Cu" "F.Mask" "F.Paste")
			(net 56 "/2xRJ45/Ethernet_P0.D1+")
			(pinfunction "P0_A_P")
			(pintype "bidirectional")
		)
		(pad "B42" smd circle
			(at 10.25 -9.085 180)
			(size 0.5 0.5)
			(layers "F.Cu" "F.Mask" "F.Paste")
			(net 253 "unconnected-(U9G-RSVDB42_NC-PadB42)")
			(pinfunction "RSVDB42_NC")
			(pintype "passive+no_connect")
		)
		(pad "C1" smd circle
			(at -10.25 -8.22 180)
			(size 0.5 0.5)
			(layers "F.Cu" "F.Mask" "F.Paste")
			(net 29 "/X710-AT2 10GbE/25MHZ_OSC.+")
			(pinfunction "REFCLKIN_P")
			(pintype "input")
		)
		(pad "C3" smd circle
			(at -9.25 -8.22 180)
			(size 0.5 0.5)
			(layers "F.Cu" "F.Mask" "F.Paste")
			(net 31 "/X710-AT2 10GbE/25MHZ_OSC.-")
			(pinfunction "REFCLKIN_N")
			(pintype "input")
		)
		(pad "C5" smd circle
			(at -8.25 -8.22 180)
			(size 0.5 0.5)
			(layers "F.Cu" "F.Mask" "F.Paste")
			(net 28 "GND")
			(pinfunction "VSSA")
			(pintype "passive")
		)
		(pad "C7" smd circle
			(at -7.25 -8.22 180)
			(size 0.5 0.5)
			(layers "F.Cu" "F.Mask" "F.Paste")
			(net 28 "GND")
			(pinfunction "VSSA")
			(pintype "passive")
		)
		(pad "C9" smd circle
			(at -6.25 -8.22 180)
			(size 0.5 0.5)
			(layers "F.Cu" "F.Mask" "F.Paste")
			(net 28 "GND")
			(pinfunction "VSSA")
			(pintype "passive")
		)
		(pad "C11" smd circle
			(at -5.25 -8.22 180)
			(size 0.5 0.5)
			(layers "F.Cu" "F.Mask" "F.Paste")
			(net 28 "GND")
			(pinfunction "VSSA")
			(pintype "passive")
		)
		(pad "C13" smd circle
			(at -4.25 -8.22 180)
			(size 0.5 0.5)
			(layers "F.Cu" "F.Mask" "F.Paste")
			(net 28 "GND")
			(pinfunction "VSSA")
			(pintype "passive")
		)
		(pad "C15" smd circle
			(at -3.25 -8.22 180)
			(size 0.5 0.5)
			(layers "F.Cu" "F.Mask" "F.Paste")
			(net 28 "GND")
			(pinfunction "VSSA")
			(pintype "passive")
		)
		(pad "C17" smd circle
			(at -2.25 -8.22 180)
			(size 0.5 0.5)
			(layers "F.Cu" "F.Mask" "F.Paste")
			(net 28 "GND")
			(pinfunction "VSSA")
			(pintype "passive")
		)
		(pad "C19" smd circle
			(at -1.25 -8.22 180)
			(size 0.5 0.5)
			(layers "F.Cu" "F.Mask" "F.Paste")
			(net 28 "GND")
			(pinfunction "VSSA")
			(pintype "passive")
		)
		(pad "C21" smd circle
			(at -0.25 -8.22 180)
			(size 0.5 0.5)
			(layers "F.Cu" "F.Mask" "F.Paste")
			(net 195 "unconnected-(U9G-RSVDC21_NC-PadC21)")
			(pinfunction "RSVDC21_NC")
			(pintype "passive+no_connect")
		)
		(pad "C23" smd circle
			(at 0.75 -8.22 180)
			(size 0.5 0.5)
			(layers "F.Cu" "F.Mask" "F.Paste")
			(net 14 "P1_AVDDL")
			(pinfunction "P1_AVDDL")
			(pintype "power_in")
		)
		(pad "C25" smd circle
			(at 1.75 -8.22 180)
			(size 0.5 0.5)
			(layers "F.Cu" "F.Mask" "F.Paste")
			(net 14 "P1_AVDDL")
			(pinfunction "P1_AVDDL")
			(pintype "passive")
		)
		(pad "C27" smd circle
			(at 2.75 -8.22 180)
			(size 0.5 0.5)
			(layers "F.Cu" "F.Mask" "F.Paste")
			(net 14 "P1_AVDDL")
			(pinfunction "P1_AVDDL")
			(pintype "passive")
		)
		(pad "C29" smd circle
			(at 3.75 -8.22 180)
			(size 0.5 0.5)
			(layers "F.Cu" "F.Mask" "F.Paste")
			(net 14 "P1_AVDDL")
			(pinfunction "P1_AVDDL")
			(pintype "passive")
		)
		(pad "C31" smd circle
			(at 4.75 -8.22 180)
			(size 0.5 0.5)
			(layers "F.Cu" "F.Mask" "F.Paste")
			(net 28 "GND")
			(pinfunction "AVSS")
			(pintype "passive")
		)
		(pad "C33" smd circle
			(at 5.75 -8.22 180)
			(size 0.5 0.5)
			(layers "F.Cu" "F.Mask" "F.Paste")
			(net 5 "P0_AVDDL")
			(pinfunction "P0_AVDDL")
			(pintype "power_in")
		)
		(pad "C35" smd circle
			(at 6.75 -8.22 180)
			(size 0.5 0.5)
			(layers "F.Cu" "F.Mask" "F.Paste")
			(net 5 "P0_AVDDL")
			(pinfunction "P0_AVDDL")
			(pintype "passive")
		)
		(pad "C37" smd circle
			(at 7.75 -8.22 180)
			(size 0.5 0.5)
			(layers "F.Cu" "F.Mask" "F.Paste")
			(net 5 "P0_AVDDL")
			(pinfunction "P0_AVDDL")
			(pintype "passive")
		)
		(pad "C39" smd circle
			(at 8.75 -8.22 180)
			(size 0.5 0.5)
			(layers "F.Cu" "F.Mask" "F.Paste")
			(net 5 "P0_AVDDL")
			(pinfunction "P0_AVDDL")
			(pintype "passive")
		)
		(pad "C41" smd circle
			(at 9.75 -8.22 180)
			(size 0.5 0.5)
			(layers "F.Cu" "F.Mask" "F.Paste")
			(net 28 "GND")
			(pinfunction "AVSS")
			(pintype "passive")
		)
		(pad "D2" smd circle
			(at -9.75 -7.355 180)
			(size 0.5 0.5)
			(layers "F.Cu" "F.Mask" "F.Paste")
			(net 290 "/X710-AT2 Misc/~{DEV_DIS}")
			(pinfunction "~{DEV_DIS}")
			(pintype "tri_state")
		)
		(pad "D4" smd circle
			(at -8.75 -7.355 180)
			(size 0.5 0.5)
			(layers "F.Cu" "F.Mask" "F.Paste")
			(net 383 "/X710-AT2 Misc/REFCLK_SEL")
			(pinfunction "REFCLK_SEL")
			(pintype "input")
		)
		(pad "D6" smd circle
			(at -7.75 -7.355 180)
			(size 0.5 0.5)
			(layers "F.Cu" "F.Mask" "F.Paste")
			(net 28 "GND")
			(pinfunction "RSVDD6_VSS")
			(pintype "passive")
		)
		(pad "D8" smd circle
			(at -6.75 -7.355 180)
			(size 0.5 0.5)
			(layers "F.Cu" "F.Mask" "F.Paste")
			(net 131 "/X710-AT2 RSVD/RSVDD8_1P88V")
			(pinfunction "RSVDD8_1P88V")
			(pintype "passive")
		)
		(pad "D10" smd circle
			(at -5.75 -7.355 180)
			(size 0.5 0.5)
			(layers "F.Cu" "F.Mask" "F.Paste")
			(net 295 "/X710-AT2 Misc/XTAL_BYPASS")
			(pinfunction "XTAL_BYPASS")
			(pintype "passive")
		)
		(pad "D12" smd circle
			(at -4.75 -7.355 180)
			(size 0.5 0.5)
			(layers "F.Cu" "F.Mask" "F.Paste")
			(net 384 "/X710-AT2 Misc/~{PHY_RESET}")
			(pinfunction "~{RESET}")
			(pintype "input")
		)
		(pad "D14" smd circle
			(at -3.75 -7.355 180)
			(size 0.5 0.5)
			(layers "F.Cu" "F.Mask" "F.Paste")
			(net 28 "GND")
			(pinfunction "RSVDD14")
			(pintype "input")
		)
		(pad "D16" smd circle
			(at -2.75 -7.355 180)
			(size 0.5 0.5)
			(layers "F.Cu" "F.Mask" "F.Paste")
			(net 135 "/X710-AT2 Misc/PHY_TMS")
			(pinfunction "PHY_TMS")
			(pintype "input")
		)
		(pad "D18" smd circle
			(at -1.75 -7.355 180)
			(size 0.5 0.5)
			(layers "F.Cu" "F.Mask" "F.Paste")
			(net 116 "/X710-AT2 Misc/~{PHY_TRST}")
			(pinfunction "~{PHY_TRST}")
			(pintype "input")
		)
		(pad "D20" smd circle
			(at -0.75 -7.355 180)
			(size 0.5 0.5)
			(layers "F.Cu" "F.Mask" "F.Paste")
			(net 250 "unconnected-(U9G-RSVDD20_NC-PadD20)")
			(pinfunction "RSVDD20_NC")
			(pintype "passive+no_connect")
		)
		(pad "D22" smd circle
			(at 0.25 -7.355 180)
			(size 0.5 0.5)
			(layers "F.Cu" "F.Mask" "F.Paste")
			(net 28 "GND")
			(pinfunction "RSVDD22_VSS")
			(pintype "passive")
		)
		(pad "D24" smd circle
			(at 1.25 -7.355 180)
			(size 0.5 0.5)
			(layers "F.Cu" "F.Mask" "F.Paste")
			(net 28 "GND")
			(pinfunction "AVSS")
			(pintype "passive")
		)
		(pad "D26" smd circle
			(at 2.25 -7.355 180)
			(size 0.5 0.5)
			(layers "F.Cu" "F.Mask" "F.Paste")
			(net 28 "GND")
			(pinfunction "AVSS")
			(pintype "passive")
		)
		(pad "D28" smd circle
			(at 3.25 -7.355 180)
			(size 0.5 0.5)
			(layers "F.Cu" "F.Mask" "F.Paste")
			(net 28 "GND")
			(pinfunction "AVSS")
			(pintype "passive")
		)
		(pad "D30" smd circle
			(at 4.25 -7.355 180)
			(size 0.5 0.5)
			(layers "F.Cu" "F.Mask" "F.Paste")
			(net 10 "AVDDH")
			(pinfunction "BIAS_AVDDH")
			(pintype "power_in")
		)
		(pad "D32" smd circle
			(at 5.25 -7.355 180)
			(size 0.5 0.5)
			(layers "F.Cu" "F.Mask" "F.Paste")
			(net 259 "unconnected-(U9G-RSVDD32_NC-PadD32)")
			(pinfunction "RSVDD32_NC")
			(pintype "passive+no_connect")
		)
		(pad "D34" smd circle
			(at 6.25 -7.355 180)
			(size 0.5 0.5)
			(layers "F.Cu" "F.Mask" "F.Paste")
			(net 23 "XGB_AVDDH")
			(pinfunction "XGB_AVDDH")
			(pintype "power_in")
		)
		(pad "D36" smd circle
			(at 7.25 -7.355 180)
			(size 0.5 0.5)
			(layers "F.Cu" "F.Mask" "F.Paste")
			(net 28 "GND")
			(pinfunction "AVSS")
			(pintype "passive")
		)
		(pad "D38" smd circle
			(at 8.25 -7.355 180)
			(size 0.5 0.5)
			(layers "F.Cu" "F.Mask" "F.Paste")
			(net 28 "GND")
			(pinfunction "AVSS")
			(pintype "passive")
		)
	)
)
